(kicad_pcb
	(version 20260206)
	(generator "pcbnew")
	(generator_version "10.0")
	(general
		(thickness 1.6)
		(legacy_teardrops no)
	)
	(paper "A4")
	(title_block
		(title "01162023_DA0F0TEBIF0_F0T_Expander_BD_F_brd_V02_OCP.brd")
		(comment 1 "Grand Teton / footprints 6971-6977 of 9728")
	)
	(layers
		(0 "F.Cu" signal "TOP")
		(4 "In1.Cu" signal "GND")
		(6 "In2.Cu" signal "VCC")
		(8 "In3.Cu" signal "VCC1")
		(10 "In4.Cu" signal "GND1")
		(12 "In5.Cu" signal "IN1")
		(14 "In6.Cu" signal "GND2")
		(16 "In7.Cu" signal "IN2")
		(18 "In8.Cu" signal "GND3")
		(20 "In9.Cu" signal "IN3")
		(22 "In10.Cu" signal "GND4")
		(24 "In11.Cu" signal "IN4")
		(26 "In12.Cu" signal "GND5")
		(28 "In13.Cu" signal "IN5")
		(30 "In14.Cu" signal "GND6")
		(32 "In15.Cu" signal "IN6")
		(34 "In16.Cu" signal "GND7")
		(2 "B.Cu" signal "BOTTOM")
		(9 "F.Adhes" user "F.Adhesive")
		(11 "B.Adhes" user "B.Adhesive")
		(13 "F.Paste" user "Package Geometry/Pastemask Top")
		(15 "B.Paste" user "Package Geometry/Pastemask Bottom")
		(5 "F.SilkS" user "Ref Des/Silkscreen Top")
		(7 "B.SilkS" user "Ref Des/Silkscreen Bottom")
		(1 "F.Mask" user "Board Geometry/Soldermask Top")
		(3 "B.Mask" user "Board Geometry/Soldermask Bottom")
		(17 "Dwgs.User" user "User.Drawings")
		(19 "Cmts.User" user "User.Comments")
		(21 "Eco1.User" user "User.Eco1")
		(23 "Eco2.User" user "User.Eco2")
		(25 "Edge.Cuts" user "Board Geometry/Outline")
		(27 "Margin" user)
		(31 "F.CrtYd" user "Package Geometry/Place Bound Top")
		(29 "B.CrtYd" user "Package Geometry/Place Bound Bottom")
		(35 "F.Fab" user "Ref Des/Assembly Top")
		(33 "B.Fab" user "Ref Des/Assembly Bottom")
	)
	(footprint ""
		(layer "F.Cu")
		(at 399.91157 -71.458074 -90)
		(property "Reference" "PD117"
			(at 4.300474 -2.7813 90)
			(unlocked yes)
			(layer "F.SilkS")
			(effects
				(font
					(size 0.7874 0.5842)
					(thickness 0.1524)
				)
				(justify left)
			)
		)
		(property "Value" ""
			(at 0 0 270)
			(layer "F.Fab")
			(effects
				(font
					(size 1.27 1.27)
				)
			)
		)
		(duplicate_pad_numbers_are_jumpers no)
		(fp_line
			(start -3.656584 1.970024)
			(end 4.240784 1.970024)
			(stroke
				(width 0.1524)
				(type default)
			)
			(layer "F.SilkS")
		)
		(fp_line
			(start 4.240784 1.970024)
			(end 4.240784 -1.970024)
			(stroke
				(width 0.1524)
				(type default)
			)
			(layer "F.SilkS")
		)
		(fp_line
			(start -3.656584 -1.970024)
			(end -3.656584 1.970024)
			(stroke
				(width 0.1524)
				(type default)
			)
			(layer "F.SilkS")
		)
		(fp_line
			(start 4.240784 -1.970024)
			(end -3.656584 -1.970024)
			(stroke
				(width 0.1524)
				(type default)
			)
			(layer "F.SilkS")
		)
		(fp_poly
			(pts
				(xy 3.580384 1.970024) (xy 3.580384 -1.970024) (xy 4.240784 -1.970024) (xy 4.240784 1.970024)
			)
			(stroke
				(width 0)
				(type default)
			)
			(fill yes)
			(layer "F.SilkS")
		)
		(fp_line
			(start -2.3749 1.970024)
			(end 2.3749 1.970024)
			(stroke
				(width 0.1)
				(type default)
			)
			(layer "F.Fab")
		)
		(fp_line
			(start 2.3749 1.970024)
			(end 2.3749 -1.970024)
			(stroke
				(width 0.1)
				(type default)
			)
			(layer "F.Fab")
		)
		(fp_line
			(start -2.3749 -1.970024)
			(end -2.3749 1.970024)
			(stroke
				(width 0.1)
				(type default)
			)
			(layer "F.Fab")
		)
		(fp_line
			(start 2.3749 -1.970024)
			(end -2.3749 -1.970024)
			(stroke
				(width 0.1)
				(type default)
			)
			(layer "F.Fab")
		)
		(fp_text user "+"
			(at -4.9784 -0.23495 270)
			(unlocked yes)
			(layer "F.Fab")
			(effects
				(font
					(size 1.905 1.4224)
					(thickness 0.1524)
				)
				(justify left)
			)
		)
		(fp_text user "-"
			(at 4.1656 -0.23495 270)
			(unlocked yes)
			(layer "F.Fab")
			(effects
				(font
					(size 1.905 1.4224)
					(thickness 0.1524)
				)
				(justify left)
			)
		)
		(pad "A" smd rect
			(at -2.450084 0 270)
			(size 2.159 2.2606)
			(layers "F.Cu" "F.Mask" "F.Paste")
			(net "GND")
		)
		(pad "C" smd rect
			(at 2.450084 0 270)
			(size 2.159 2.2606)
			(layers "F.Cu" "F.Mask" "F.Paste")
			(net "P12V_AUX")
		)
	)
	(footprint ""
		(layer "F.Cu")
		(at 456.957938 -275.725636 135)
		(property "Reference" "C828"
			(at 0 0 135)
			(layer "F.SilkS")
			(hide yes)
			(effects
				(font
					(size 1.27 1.27)
				)
			)
		)
		(property "Value" ""
			(at 0 0 135)
			(layer "F.Fab")
			(effects
				(font
					(size 1.27 1.27)
				)
			)
		)
		(duplicate_pad_numbers_are_jumpers no)
		(fp_line
			(start 0.787389 -0.406267)
			(end 0.787389 0.406267)
			(stroke
				(width 0.1524)
				(type default)
			)
			(layer "F.SilkS")
		)
		(fp_line
			(start 0.787389 0.406267)
			(end -0.787389 0.406267)
			(stroke
				(width 0.1524)
				(type default)
			)
			(layer "F.SilkS")
		)
		(fp_line
			(start -0.787389 -0.406267)
			(end 0.787389 -0.406267)
			(stroke
				(width 0.1524)
				(type default)
			)
			(layer "F.SilkS")
		)
		(fp_line
			(start -0.787389 0.406267)
			(end -0.787389 -0.406267)
			(stroke
				(width 0.1524)
				(type default)
			)
			(layer "F.SilkS")
		)
		(fp_line
			(start 0.679446 -0.30479)
			(end 0.679446 0.30479)
			(stroke
				(width 0.1)
				(type default)
			)
			(layer "F.Fab")
		)
		(fp_line
			(start 0.120515 -0.30479)
			(end 0.679446 -0.30479)
			(stroke
				(width 0.1)
				(type default)
			)
			(layer "F.Fab")
		)
		(fp_line
			(start 0.120695 -0.279466)
			(end 0.120515 -0.30479)
			(stroke
				(width 0.1)
				(type default)
			)
			(layer "F.Fab")
		)
		(fp_line
			(start 0.679446 0.30479)
			(end 0.120515 0.30479)
			(stroke
				(width 0.1)
				(type default)
			)
			(layer "F.Fab")
		)
		(fp_line
			(start -0.120695 -0.304969)
			(end -0.120695 -0.279466)
			(stroke
				(width 0.1)
				(type default)
			)
			(layer "F.Fab")
		)
		(fp_line
			(start -0.120695 -0.279466)
			(end 0.120695 -0.279466)
			(stroke
				(width 0.1)
				(type default)
			)
			(layer "F.Fab")
		)
		(fp_line
			(start 0.120335 0.279466)
			(end -0.120695 0.279466)
			(stroke
				(width 0.1)
				(type default)
			)
			(layer "F.Fab")
		)
		(fp_line
			(start 0.120515 0.30479)
			(end 0.120335 0.279466)
			(stroke
				(width 0.1)
				(type default)
			)
			(layer "F.Fab")
		)
		(fp_line
			(start -0.679446 -0.305149)
			(end -0.120695 -0.304969)
			(stroke
				(width 0.1)
				(type default)
			)
			(layer "F.Fab")
		)
		(fp_line
			(start -0.120695 0.279466)
			(end -0.120515 0.30479)
			(stroke
				(width 0.1)
				(type default)
			)
			(layer "F.Fab")
		)
		(fp_line
			(start -0.120515 0.30479)
			(end -0.679446 0.30479)
			(stroke
				(width 0.1)
				(type default)
			)
			(layer "F.Fab")
		)
		(fp_line
			(start -0.679446 0.30479)
			(end -0.679446 -0.305149)
			(stroke
				(width 0.1)
				(type default)
			)
			(layer "F.Fab")
		)
		(pad "1" smd circle
			(at -0.40005 0 135)
			(size 0 0)
			(layers "F.Cu" "F.Mask" "F.Paste")
			(net "P12V_PEX3_P1V25_VIN_P")
		)
		(pad "2" smd circle
			(at 0.40005 0 135)
			(size 0 0)
			(layers "F.Cu" "F.Mask" "F.Paste")
			(net "P12V_PEX3_P1V25_VIN_N")
		)
	)
	(footprint ""
		(layer "F.Cu")
		(at 365.506 -200.787 180)
		(property "Reference" "R4686"
			(at 0 0 180)
			(layer "F.SilkS")
			(hide yes)
			(effects
				(font
					(size 1.27 1.27)
				)
			)
		)
		(property "Value" ""
			(at 0 0 180)
			(layer "F.Fab")
			(effects
				(font
					(size 1.27 1.27)
				)
			)
		)
		(duplicate_pad_numbers_are_jumpers no)
		(fp_line
			(start 0.7874 0.4064)
			(end -0.7874 0.4064)
			(stroke
				(width 0.1524)
				(type default)
			)
			(layer "F.SilkS")
		)
		(fp_line
			(start 0.7874 -0.4064)
			(end 0.7874 0.4064)
			(stroke
				(width 0.1524)
				(type default)
			)
			(layer "F.SilkS")
		)
		(fp_line
			(start -0.7874 0.4064)
			(end -0.7874 -0.4064)
			(stroke
				(width 0.1524)
				(type default)
			)
			(layer "F.SilkS")
		)
		(fp_line
			(start -0.7874 -0.4064)
			(end 0.7874 -0.4064)
			(stroke
				(width 0.1524)
				(type default)
			)
			(layer "F.SilkS")
		)
		(fp_line
			(start 0.67945 0.3048)
			(end 0.120396 0.3048)
			(stroke
				(width 0.1)
				(type default)
			)
			(layer "F.Fab")
		)
		(fp_line
			(start 0.67945 -0.3048)
			(end 0.67945 0.3048)
			(stroke
				(width 0.1)
				(type default)
			)
			(layer "F.Fab")
		)
		(fp_line
			(start 0.12065 -0.2794)
			(end 0.12065 -0.3048)
			(stroke
				(width 0.1)
				(type default)
			)
			(layer "F.Fab")
		)
		(fp_line
			(start 0.12065 -0.3048)
			(end 0.67945 -0.3048)
			(stroke
				(width 0.1)
				(type default)
			)
			(layer "F.Fab")
		)
		(fp_line
			(start 0.120396 0.3048)
			(end 0.120396 0.2794)
			(stroke
				(width 0.1)
				(type default)
			)
			(layer "F.Fab")
		)
		(fp_line
			(start 0.120396 0.2794)
			(end -0.12065 0.2794)
			(stroke
				(width 0.1)
				(type default)
			)
			(layer "F.Fab")
		)
		(fp_line
			(start -0.12065 0.3048)
			(end -0.67945 0.3048)
			(stroke
				(width 0.1)
				(type default)
			)
			(layer "F.Fab")
		)
		(fp_line
			(start -0.12065 0.2794)
			(end -0.12065 0.3048)
			(stroke
				(width 0.1)
				(type default)
			)
			(layer "F.Fab")
		)
		(fp_line
			(start -0.12065 -0.2794)
			(end 0.12065 -0.2794)
			(stroke
				(width 0.1)
				(type default)
			)
			(layer "F.Fab")
		)
		(fp_line
			(start -0.12065 -0.305054)
			(end -0.12065 -0.2794)
			(stroke
				(width 0.1)
				(type default)
			)
			(layer "F.Fab")
		)
		(fp_line
			(start -0.67945 0.3048)
			(end -0.67945 -0.305054)
			(stroke
				(width 0.1)
				(type default)
			)
			(layer "F.Fab")
		)
		(fp_line
			(start -0.67945 -0.305054)
			(end -0.12065 -0.305054)
			(stroke
				(width 0.1)
				(type default)
			)
			(layer "F.Fab")
		)
		(pad "1" smd circle
			(at -0.40005 0 180)
			(size 0 0)
			(layers "F.Cu" "F.Mask" "F.Paste")
			(net "PRSNT_SSD4_FPGA_PCA9555_N")
		)
		(pad "2" smd circle
			(at 0.40005 0 180)
			(size 0 0)
			(layers "F.Cu" "F.Mask" "F.Paste")
			(net "PRSNT_SSD4_FPGA_R_N")
		)
	)
	(footprint ""
		(layer "F.Cu")
		(at 220.366844 -98.806 90)
		(property "Reference" "R721"
			(at 0 0 90)
			(layer "F.SilkS")
			(hide yes)
			(effects
				(font
					(size 1.27 1.27)
				)
			)
		)
		(property "Value" ""
			(at 0 0 90)
			(layer "F.Fab")
			(effects
				(font
					(size 1.27 1.27)
				)
			)
		)
		(duplicate_pad_numbers_are_jumpers no)
		(fp_line
			(start 0.7874 -0.4064)
			(end 0.7874 0.4064)
			(stroke
				(width 0.1524)
				(type default)
			)
			(layer "F.SilkS")
		)
		(fp_line
			(start -0.7874 -0.4064)
			(end 0.7874 -0.4064)
			(stroke
				(width 0.1524)
				(type default)
			)
			(layer "F.SilkS")
		)
		(fp_line
			(start 0.7874 0.4064)
			(end -0.7874 0.4064)
			(stroke
				(width 0.1524)
				(type default)
			)
			(layer "F.SilkS")
		)
		(fp_line
			(start -0.7874 0.4064)
			(end -0.7874 -0.4064)
			(stroke
				(width 0.1524)
				(type default)
			)
			(layer "F.SilkS")
		)
		(fp_line
			(start -0.12065 -0.305054)
			(end -0.12065 -0.2794)
			(stroke
				(width 0.1)
				(type default)
			)
			(layer "F.Fab")
		)
		(fp_line
			(start -0.67945 -0.305054)
			(end -0.12065 -0.305054)
			(stroke
				(width 0.1)
				(type default)
			)
			(layer "F.Fab")
		)
		(fp_line
			(start 0.67945 -0.3048)
			(end 0.67945 0.3048)
			(stroke
				(width 0.1)
				(type default)
			)
			(layer "F.Fab")
		)
		(fp_line
			(start 0.12065 -0.3048)
			(end 0.67945 -0.3048)
			(stroke
				(width 0.1)
				(type default)
			)
			(layer "F.Fab")
		)
		(fp_line
			(start 0.12065 -0.2794)
			(end 0.12065 -0.3048)
			(stroke
				(width 0.1)
				(type default)
			)
			(layer "F.Fab")
		)
		(fp_line
			(start -0.12065 -0.2794)
			(end 0.12065 -0.2794)
			(stroke
				(width 0.1)
				(type default)
			)
			(layer "F.Fab")
		)
		(fp_line
			(start 0.120396 0.2794)
			(end -0.12065 0.2794)
			(stroke
				(width 0.1)
				(type default)
			)
			(layer "F.Fab")
		)
		(fp_line
			(start -0.12065 0.2794)
			(end -0.12065 0.3048)
			(stroke
				(width 0.1)
				(type default)
			)
			(layer "F.Fab")
		)
		(fp_line
			(start 0.67945 0.3048)
			(end 0.120396 0.3048)
			(stroke
				(width 0.1)
				(type default)
			)
			(layer "F.Fab")
		)
		(fp_line
			(start 0.120396 0.3048)
			(end 0.120396 0.2794)
			(stroke
				(width 0.1)
				(type default)
			)
			(layer "F.Fab")
		)
		(fp_line
			(start -0.12065 0.3048)
			(end -0.67945 0.3048)
			(stroke
				(width 0.1)
				(type default)
			)
			(layer "F.Fab")
		)
		(fp_line
			(start -0.67945 0.3048)
			(end -0.67945 -0.305054)
			(stroke
				(width 0.1)
				(type default)
			)
			(layer "F.Fab")
		)
		(pad "1" smd circle
			(at -0.40005 0 90)
			(size 0 0)
			(layers "F.Cu" "F.Mask" "F.Paste")
			(net "SMB_BIC_I2C6_MUX_NIC_ADC_R_SDA")
		)
		(pad "2" smd circle
			(at 0.40005 0 90)
			(size 0 0)
			(layers "F.Cu" "F.Mask" "F.Paste")
			(net "SMB_NIC3_ADC_SDA")
		)
	)
	(footprint ""
		(layer "F.Cu")
		(at 257.811524 -71.458074 -90)
		(property "Reference" "PD36"
			(at 4.300474 -2.742946 90)
			(unlocked yes)
			(layer "F.SilkS")
			(effects
				(font
					(size 0.7874 0.5842)
					(thickness 0.1524)
				)
				(justify left)
			)
		)
		(property "Value" ""
			(at 0 0 270)
			(layer "F.Fab")
			(effects
				(font
					(size 1.27 1.27)
				)
			)
		)
		(duplicate_pad_numbers_are_jumpers no)
		(fp_line
			(start -3.656584 1.970024)
			(end 4.240784 1.970024)
			(stroke
				(width 0.1524)
				(type default)
			)
			(layer "F.SilkS")
		)
		(fp_line
			(start 4.240784 1.970024)
			(end 4.240784 -1.970024)
			(stroke
				(width 0.1524)
				(type default)
			)
			(layer "F.SilkS")
		)
		(fp_line
			(start -3.656584 -1.970024)
			(end -3.656584 1.970024)
			(stroke
				(width 0.1524)
				(type default)
			)
			(layer "F.SilkS")
		)
		(fp_line
			(start 4.240784 -1.970024)
			(end -3.656584 -1.970024)
			(stroke
				(width 0.1524)
				(type default)
			)
			(layer "F.SilkS")
		)
		(fp_poly
			(pts
				(xy 3.580384 1.970024) (xy 3.580384 -1.970024) (xy 4.240784 -1.970024) (xy 4.240784 1.970024)
			)
			(stroke
				(width 0)
				(type default)
			)
			(fill yes)
			(layer "F.SilkS")
		)
		(fp_line
			(start -2.3749 1.970024)
			(end 2.3749 1.970024)
			(stroke
				(width 0.1)
				(type default)
			)
			(layer "F.Fab")
		)
		(fp_line
			(start 2.3749 1.970024)
			(end 2.3749 -1.970024)
			(stroke
				(width 0.1)
				(type default)
			)
			(layer "F.Fab")
		)
		(fp_line
			(start -2.3749 -1.970024)
			(end -2.3749 1.970024)
			(stroke
				(width 0.1)
				(type default)
			)
			(layer "F.Fab")
		)
		(fp_line
			(start 2.3749 -1.970024)
			(end -2.3749 -1.970024)
			(stroke
				(width 0.1)
				(type default)
			)
			(layer "F.Fab")
		)
		(fp_text user "+"
			(at -4.9784 -0.23495 270)
			(unlocked yes)
			(layer "F.Fab")
			(effects
				(font
					(size 1.905 1.4224)
					(thickness 0.1524)
				)
				(justify left)
			)
		)
		(fp_text user "-"
			(at 4.1656 -0.23495 270)
			(unlocked yes)
			(layer "F.Fab")
			(effects
				(font
					(size 1.905 1.4224)
					(thickness 0.1524)
				)
				(justify left)
			)
		)
		(pad "A" smd rect
			(at -2.450084 0 270)
			(size 2.159 2.2606)
			(layers "F.Cu" "F.Mask" "F.Paste")
			(net "GND")
		)
		(pad "C" smd rect
			(at 2.450084 0 270)
			(size 2.159 2.2606)
			(layers "F.Cu" "F.Mask" "F.Paste")
			(net "P12V_AUX")
		)
	)
	(footprint ""
		(layer "F.Cu")
		(at 424.814492 -350.098614 90)
		(property "Reference" "C810"
			(at 0 0 90)
			(layer "F.SilkS")
			(hide yes)
			(effects
				(font
					(size 1.27 1.27)
				)
			)
		)
		(property "Value" ""
			(at 0 0 90)
			(layer "F.Fab")
			(effects
				(font
					(size 1.27 1.27)
				)
			)
		)
		(duplicate_pad_numbers_are_jumpers no)
		(fp_line
			(start 0.299974 -0.150114)
			(end 0.299974 0.150114)
			(stroke
				(width 0.1)
				(type default)
			)
			(layer "F.Fab")
		)
		(fp_line
			(start -0.299974 -0.150114)
			(end 0.299974 -0.150114)
			(stroke
				(width 0.1)
				(type default)
			)
			(layer "F.Fab")
		)
		(fp_line
			(start 0.299974 0.150114)
			(end -0.299974 0.150114)
			(stroke
				(width 0.1)
				(type default)
			)
			(layer "F.Fab")
		)
		(fp_line
			(start -0.299974 0.150114)
			(end -0.299974 -0.150114)
			(stroke
				(width 0.1)
				(type default)
			)
			(layer "F.Fab")
		)
		(pad "1" smd rect
			(at -0.2667 0 90)
			(size 0.3048 0.381)
			(layers "F.Cu" "F.Mask" "F.Paste")
			(net "P5E_PEX3_STN7_TX_DP<119>")
		)
		(pad "2" smd rect
			(at 0.2667 0 90)
			(size 0.3048 0.381)
			(layers "F.Cu" "F.Mask" "F.Paste")
			(net "P5E_PEX3_STN7_TX_C_DP<119>")
		)
	)
	(footprint ""
		(layer "F.Cu")
		(at 364.259876 -254.385826)
		(property "Reference" "R3059"
			(at 0 0 0)
			(layer "F.SilkS")
			(hide yes)
			(effects
				(font
					(size 1.27 1.27)
				)
			)
		)
		(property "Value" ""
			(at 0 0 0)
			(layer "F.Fab")
			(effects
				(font
					(size 1.27 1.27)
				)
			)
		)
		(duplicate_pad_numbers_are_jumpers no)
		(fp_line
			(start -0.7874 -0.4064)
			(end 0.7874 -0.4064)
			(stroke
				(width 0.1524)
				(type default)
			)
			(layer "F.SilkS")
		)
		(fp_line
			(start -0.7874 0.4064)
			(end -0.7874 -0.4064)
			(stroke
				(width 0.1524)
				(type default)
			)
			(layer "F.SilkS")
		)
		(fp_line
			(start 0.7874 -0.4064)
			(end 0.7874 0.4064)
			(stroke
				(width 0.1524)
				(type default)
			)
			(layer "F.SilkS")
		)
		(fp_line
			(start 0.7874 0.4064)
			(end -0.7874 0.4064)
			(stroke
				(width 0.1524)
				(type default)
			)
			(layer "F.SilkS")
		)
		(fp_line
			(start -0.67945 -0.305054)
			(end -0.12065 -0.305054)
			(stroke
				(width 0.1)
				(type default)
			)
			(layer "F.Fab")
		)
		(fp_line
			(start -0.67945 0.3048)
			(end -0.67945 -0.305054)
			(stroke
				(width 0.1)
				(type default)
			)
			(layer "F.Fab")
		)
		(fp_line
			(start -0.12065 -0.305054)
			(end -0.12065 -0.2794)
			(stroke
				(width 0.1)
				(type default)
			)
			(layer "F.Fab")
		)
		(fp_line
			(start -0.12065 -0.2794)
			(end 0.12065 -0.2794)
			(stroke
				(width 0.1)
				(type default)
			)
			(layer "F.Fab")
		)
		(fp_line
			(start -0.12065 0.2794)
			(end -0.12065 0.3048)
			(stroke
				(width 0.1)
				(type default)
			)
			(layer "F.Fab")
		)
		(fp_line
			(start -0.12065 0.3048)
			(end -0.67945 0.3048)
			(stroke
				(width 0.1)
				(type default)
			)
			(layer "F.Fab")
		)
		(fp_line
			(start 0.120396 0.2794)
			(end -0.12065 0.2794)
			(stroke
				(width 0.1)
				(type default)
			)
			(layer "F.Fab")
		)
		(fp_line
			(start 0.120396 0.3048)
			(end 0.120396 0.2794)
			(stroke
				(width 0.1)
				(type default)
			)
			(layer "F.Fab")
		)
		(fp_line
			(start 0.12065 -0.3048)
			(end 0.67945 -0.3048)
			(stroke
				(width 0.1)
				(type default)
			)
			(layer "F.Fab")
		)
		(fp_line
			(start 0.12065 -0.2794)
			(end 0.12065 -0.3048)
			(stroke
				(width 0.1)
				(type default)
			)
			(layer "F.Fab")
		)
		(fp_line
			(start 0.67945 -0.3048)
			(end 0.67945 0.3048)
			(stroke
				(width 0.1)
				(type default)
			)
			(layer "F.Fab")
		)
		(fp_line
			(start 0.67945 0.3048)
			(end 0.120396 0.3048)
			(stroke
				(width 0.1)
				(type default)
			)
			(layer "F.Fab")
		)
		(pad "1" smd circle
			(at -0.40005 0)
			(size 0 0)
			(layers "F.Cu" "F.Mask" "F.Paste")
			(net "PWR_EN_PEX_R")
		)
		(pad "2" smd circle
			(at 0.40005 0)
			(size 0 0)
			(layers "F.Cu" "F.Mask" "F.Paste")
			(net "PWR_EN_PEX")
		)
	)
)
